#ISCELL
  pure_quanta quanta_title_block_c *
  *
#CELL
  pure_quanta q_cap *
  page135_i100
#ISCELL
  logical_power universal_gnd *
  page135_i103
#CELL
  pure_quanta q_res *
  page135_i106
#CELL
  pure_quanta q_res *
  page135_i107
#ISCELL
  logical_power universal_power *
  page135_i108
#CELL
  pure_quanta q_res *
  page135_i109
#CELL
  pure_quanta q_res *
  page135_i110
#ISCELL
  standard offpage *
  page135_i111
#ISCELL
  standard offpage *
  page135_i112
#ISCELL
  standard offpage *
  page135_i113
#ISCELL
  standard offpage *
  page135_i114
#CELL
  pure_quanta 74lvc1g66gv *
  page135_i115
#ISCELL
  standard offpage *
  page135_i23
#ISCELL
  logical_power universal_gnd *
  page135_i27
#CELL
  pure_quanta nc7sb3157 *
  page135_i58
#ISCELL
  standard offpage *
  page135_i59
#ISCELL
  logical_power universal_power *
  page135_i60
#CELL
  pure_quanta q_cap *
  page135_i61
#ISCELL
  standard offpage *
  page135_i63
#ISCELL
  standard offpage *
  page135_i64
#CELL
  pure_quanta q_res *
  page135_i65
#CELL
  pure_quanta q_res *
  page135_i66
#ISCELL
  logical_power universal_power *
  page135_i67
#ISCELL
  logical_power universal_power *
  page135_i68
#ISCELL
  logical_power universal_gnd *
  page135_i69
#CELL
  pure_quanta q_cap *
  page135_i70
#CELL
  pure_quanta nc7sb3157 *
  page135_i71
#ISCELL
  logical_power universal_power *
  page135_i72
#ISCELL
  logical_power universal_power *
  page135_i73
#ISCELL
  logical_power universal_power *
  page135_i74
#CELL
  pure_quanta q_res *
  page135_i77
#CELL
  pure_quanta q_res *
  page135_i78
#ISCELL
  logical_power universal_gnd *
  page135_i79
#CELL
  pure_quanta q_cap *
  page135_i80
#CELL
  pure_quanta q_cap *
  page135_i81
#ISCELL
  logical_power universal_gnd *
  page135_i82
#ISCELL
  standard offpage *
  page135_i84
#ISCELL
  standard offpage *
  page135_i85
#ISCELL
  standard offpage *
  page135_i86
#ISCELL
  standard offpage *
  page135_i87
#ISCELL
  standard offpage *
  page135_i90
#ISCELL
  standard offpage *
  page135_i91
#ISCELL
  logical_power universal_gnd *
  page135_i92
#ISCELL
  logical_power universal_power *
  page135_i93
#CELL
  pure_quanta q_cap *
  page135_i94
#ISCELL
  logical_power universal_gnd *
  page135_i95
#CELL
  pure_quanta 74lvc1g02gw *
  page135_i96
#CELL
  pure_quanta q_res *
  page135_i97
#ISCELL
  logical_power universal_power *
  page135_i98
#ISCELL
  logical_power universal_gnd *
  page135_i99
